(kicad_pcb
	(version 20260206)
	(generator "pcbnew")
	(generator_version "10.0")
	(general
		(thickness 1.6)
		(legacy_teardrops no)
	)
	(paper "A4")
	(title_block
		(title "01162023_DA0F0TEBIF0_F0T_Expander_BD_F_brd_V02_OCP.brd")
		(comment 1 "Grand Teton / footprints 410-416 of 9728")
	)
	(layers
		(0 "F.Cu" signal "TOP")
		(4 "In1.Cu" signal "GND")
		(6 "In2.Cu" signal "VCC")
		(8 "In3.Cu" signal "VCC1")
		(10 "In4.Cu" signal "GND1")
		(12 "In5.Cu" signal "IN1")
		(14 "In6.Cu" signal "GND2")
		(16 "In7.Cu" signal "IN2")
		(18 "In8.Cu" signal "GND3")
		(20 "In9.Cu" signal "IN3")
		(22 "In10.Cu" signal "GND4")
		(24 "In11.Cu" signal "IN4")
		(26 "In12.Cu" signal "GND5")
		(28 "In13.Cu" signal "IN5")
		(30 "In14.Cu" signal "GND6")
		(32 "In15.Cu" signal "IN6")
		(34 "In16.Cu" signal "GND7")
		(2 "B.Cu" signal "BOTTOM")
		(9 "F.Adhes" user "F.Adhesive")
		(11 "B.Adhes" user "B.Adhesive")
		(13 "F.Paste" user "Package Geometry/Pastemask Top")
		(15 "B.Paste" user "Package Geometry/Pastemask Bottom")
		(5 "F.SilkS" user "Ref Des/Silkscreen Top")
		(7 "B.SilkS" user "Ref Des/Silkscreen Bottom")
		(1 "F.Mask" user "Board Geometry/Soldermask Top")
		(3 "B.Mask" user "Board Geometry/Soldermask Bottom")
		(17 "Dwgs.User" user "User.Drawings")
		(19 "Cmts.User" user "User.Comments")
		(21 "Eco1.User" user "User.Eco1")
		(23 "Eco2.User" user "User.Eco2")
		(25 "Edge.Cuts" user "Board Geometry/Outline")
		(27 "Margin" user)
		(31 "F.CrtYd" user "Package Geometry/Place Bound Top")
		(29 "B.CrtYd" user "Package Geometry/Place Bound Bottom")
		(35 "F.Fab" user "Ref Des/Assembly Top")
		(33 "B.Fab" user "Ref Des/Assembly Bottom")
	)
	(footprint ""
		(layer "F.Cu")
		(at 16.359632 -146.642328 -90)
		(property "Reference" "C409"
			(at 0 0 270)
			(layer "F.SilkS")
			(hide yes)
			(effects
				(font
					(size 1.27 1.27)
				)
			)
		)
		(property "Value" ""
			(at 0 0 270)
			(layer "F.Fab")
			(effects
				(font
					(size 1.27 1.27)
				)
			)
		)
		(duplicate_pad_numbers_are_jumpers no)
		(fp_line
			(start -0.7874 0.4064)
			(end -0.7874 -0.4064)
			(stroke
				(width 0.1524)
				(type default)
			)
			(layer "F.SilkS")
		)
		(fp_line
			(start 0.7874 0.4064)
			(end -0.7874 0.4064)
			(stroke
				(width 0.1524)
				(type default)
			)
			(layer "F.SilkS")
		)
		(fp_line
			(start -0.7874 -0.4064)
			(end 0.7874 -0.4064)
			(stroke
				(width 0.1524)
				(type default)
			)
			(layer "F.SilkS")
		)
		(fp_line
			(start 0.7874 -0.4064)
			(end 0.7874 0.4064)
			(stroke
				(width 0.1524)
				(type default)
			)
			(layer "F.SilkS")
		)
		(fp_line
			(start -0.67945 0.3048)
			(end -0.67945 -0.305054)
			(stroke
				(width 0.1)
				(type default)
			)
			(layer "F.Fab")
		)
		(fp_line
			(start -0.12065 0.3048)
			(end -0.67945 0.3048)
			(stroke
				(width 0.1)
				(type default)
			)
			(layer "F.Fab")
		)
		(fp_line
			(start 0.120396 0.3048)
			(end 0.120396 0.2794)
			(stroke
				(width 0.1)
				(type default)
			)
			(layer "F.Fab")
		)
		(fp_line
			(start 0.67945 0.3048)
			(end 0.120396 0.3048)
			(stroke
				(width 0.1)
				(type default)
			)
			(layer "F.Fab")
		)
		(fp_line
			(start -0.12065 0.2794)
			(end -0.12065 0.3048)
			(stroke
				(width 0.1)
				(type default)
			)
			(layer "F.Fab")
		)
		(fp_line
			(start 0.120396 0.2794)
			(end -0.12065 0.2794)
			(stroke
				(width 0.1)
				(type default)
			)
			(layer "F.Fab")
		)
		(fp_line
			(start -0.12065 -0.2794)
			(end 0.12065 -0.2794)
			(stroke
				(width 0.1)
				(type default)
			)
			(layer "F.Fab")
		)
		(fp_line
			(start 0.12065 -0.2794)
			(end 0.12065 -0.3048)
			(stroke
				(width 0.1)
				(type default)
			)
			(layer "F.Fab")
		)
		(fp_line
			(start 0.12065 -0.3048)
			(end 0.67945 -0.3048)
			(stroke
				(width 0.1)
				(type default)
			)
			(layer "F.Fab")
		)
		(fp_line
			(start 0.67945 -0.3048)
			(end 0.67945 0.3048)
			(stroke
				(width 0.1)
				(type default)
			)
			(layer "F.Fab")
		)
		(fp_line
			(start -0.67945 -0.305054)
			(end -0.12065 -0.305054)
			(stroke
				(width 0.1)
				(type default)
			)
			(layer "F.Fab")
		)
		(fp_line
			(start -0.12065 -0.305054)
			(end -0.12065 -0.2794)
			(stroke
				(width 0.1)
				(type default)
			)
			(layer "F.Fab")
		)
		(pad "1" smd circle
			(at -0.40005 0 270)
			(size 0 0)
			(layers "F.Cu" "F.Mask" "F.Paste")
			(net "P3V3_AUX")
		)
		(pad "2" smd circle
			(at 0.40005 0 270)
			(size 0 0)
			(layers "F.Cu" "F.Mask" "F.Paste")
			(net "GND")
		)
	)
	(footprint ""
		(layer "F.Cu")
		(at 257.172968 -347.68409)
		(property "Reference" "R6648"
			(at 0 0 0)
			(layer "F.SilkS")
			(hide yes)
			(effects
				(font
					(size 1.27 1.27)
				)
			)
		)
		(property "Value" ""
			(at 0 0 0)
			(layer "F.Fab")
			(effects
				(font
					(size 1.27 1.27)
				)
			)
		)
		(duplicate_pad_numbers_are_jumpers no)
		(fp_line
			(start -0.7874 -0.4064)
			(end 0.7874 -0.4064)
			(stroke
				(width 0.1524)
				(type default)
			)
			(layer "F.SilkS")
		)
		(fp_line
			(start -0.7874 0.4064)
			(end -0.7874 -0.4064)
			(stroke
				(width 0.1524)
				(type default)
			)
			(layer "F.SilkS")
		)
		(fp_line
			(start 0.7874 -0.4064)
			(end 0.7874 0.4064)
			(stroke
				(width 0.1524)
				(type default)
			)
			(layer "F.SilkS")
		)
		(fp_line
			(start 0.7874 0.4064)
			(end -0.7874 0.4064)
			(stroke
				(width 0.1524)
				(type default)
			)
			(layer "F.SilkS")
		)
		(fp_line
			(start -0.67945 -0.305054)
			(end -0.12065 -0.305054)
			(stroke
				(width 0.1)
				(type default)
			)
			(layer "F.Fab")
		)
		(fp_line
			(start -0.67945 0.3048)
			(end -0.67945 -0.305054)
			(stroke
				(width 0.1)
				(type default)
			)
			(layer "F.Fab")
		)
		(fp_line
			(start -0.12065 -0.305054)
			(end -0.12065 -0.2794)
			(stroke
				(width 0.1)
				(type default)
			)
			(layer "F.Fab")
		)
		(fp_line
			(start -0.12065 -0.2794)
			(end 0.12065 -0.2794)
			(stroke
				(width 0.1)
				(type default)
			)
			(layer "F.Fab")
		)
		(fp_line
			(start -0.12065 0.2794)
			(end -0.12065 0.3048)
			(stroke
				(width 0.1)
				(type default)
			)
			(layer "F.Fab")
		)
		(fp_line
			(start -0.12065 0.3048)
			(end -0.67945 0.3048)
			(stroke
				(width 0.1)
				(type default)
			)
			(layer "F.Fab")
		)
		(fp_line
			(start 0.120396 0.2794)
			(end -0.12065 0.2794)
			(stroke
				(width 0.1)
				(type default)
			)
			(layer "F.Fab")
		)
		(fp_line
			(start 0.120396 0.3048)
			(end 0.120396 0.2794)
			(stroke
				(width 0.1)
				(type default)
			)
			(layer "F.Fab")
		)
		(fp_line
			(start 0.12065 -0.3048)
			(end 0.67945 -0.3048)
			(stroke
				(width 0.1)
				(type default)
			)
			(layer "F.Fab")
		)
		(fp_line
			(start 0.12065 -0.2794)
			(end 0.12065 -0.3048)
			(stroke
				(width 0.1)
				(type default)
			)
			(layer "F.Fab")
		)
		(fp_line
			(start 0.67945 -0.3048)
			(end 0.67945 0.3048)
			(stroke
				(width 0.1)
				(type default)
			)
			(layer "F.Fab")
		)
		(fp_line
			(start 0.67945 0.3048)
			(end 0.120396 0.3048)
			(stroke
				(width 0.1)
				(type default)
			)
			(layer "F.Fab")
		)
		(pad "1" smd circle
			(at -0.40005 0)
			(size 0 0)
			(layers "F.Cu" "F.Mask" "F.Paste")
			(net "HSC_CSOUT")
		)
		(pad "2" smd circle
			(at 0.40005 0)
			(size 0 0)
			(layers "F.Cu" "F.Mask" "F.Paste")
			(net "A_HSC_LOW")
		)
	)
	(footprint ""
		(layer "F.Cu")
		(at 404.861268 -365.268256 -90)
		(property "Reference" "C4452"
			(at 0 0 270)
			(layer "F.SilkS")
			(hide yes)
			(effects
				(font
					(size 1.27 1.27)
				)
			)
		)
		(property "Value" ""
			(at 0 0 270)
			(layer "F.Fab")
			(effects
				(font
					(size 1.27 1.27)
				)
			)
		)
		(duplicate_pad_numbers_are_jumpers no)
		(fp_line
			(start -0.299974 0.150114)
			(end -0.299974 -0.150114)
			(stroke
				(width 0.1)
				(type default)
			)
			(layer "F.Fab")
		)
		(fp_line
			(start 0.299974 0.150114)
			(end -0.299974 0.150114)
			(stroke
				(width 0.1)
				(type default)
			)
			(layer "F.Fab")
		)
		(fp_line
			(start -0.299974 -0.150114)
			(end 0.299974 -0.150114)
			(stroke
				(width 0.1)
				(type default)
			)
			(layer "F.Fab")
		)
		(fp_line
			(start 0.299974 -0.150114)
			(end 0.299974 0.150114)
			(stroke
				(width 0.1)
				(type default)
			)
			(layer "F.Fab")
		)
		(pad "1" smd rect
			(at -0.2667 0 270)
			(size 0.3048 0.381)
			(layers "F.Cu" "F.Mask" "F.Paste")
			(net "GPU_3V3IO_RSVD1_ISO")
		)
		(pad "2" smd rect
			(at 0.2667 0 270)
			(size 0.3048 0.381)
			(layers "F.Cu" "F.Mask" "F.Paste")
			(net "GND")
		)
	)
	(footprint ""
		(layer "F.Cu")
		(at 203.838048 -291.102034 180)
		(property "Reference" "R6391"
			(at 0 0 180)
			(layer "F.SilkS")
			(hide yes)
			(effects
				(font
					(size 1.27 1.27)
				)
			)
		)
		(property "Value" ""
			(at 0 0 180)
			(layer "F.Fab")
			(effects
				(font
					(size 1.27 1.27)
				)
			)
		)
		(duplicate_pad_numbers_are_jumpers no)
		(fp_line
			(start 0.7874 0.4064)
			(end -0.7874 0.4064)
			(stroke
				(width 0.1524)
				(type default)
			)
			(layer "F.SilkS")
		)
		(fp_line
			(start 0.7874 -0.4064)
			(end 0.7874 0.4064)
			(stroke
				(width 0.1524)
				(type default)
			)
			(layer "F.SilkS")
		)
		(fp_line
			(start -0.7874 0.4064)
			(end -0.7874 -0.4064)
			(stroke
				(width 0.1524)
				(type default)
			)
			(layer "F.SilkS")
		)
		(fp_line
			(start -0.7874 -0.4064)
			(end 0.7874 -0.4064)
			(stroke
				(width 0.1524)
				(type default)
			)
			(layer "F.SilkS")
		)
		(fp_line
			(start 0.67945 0.3048)
			(end 0.120396 0.3048)
			(stroke
				(width 0.1)
				(type default)
			)
			(layer "F.Fab")
		)
		(fp_line
			(start 0.67945 -0.3048)
			(end 0.67945 0.3048)
			(stroke
				(width 0.1)
				(type default)
			)
			(layer "F.Fab")
		)
		(fp_line
			(start 0.12065 -0.2794)
			(end 0.12065 -0.3048)
			(stroke
				(width 0.1)
				(type default)
			)
			(layer "F.Fab")
		)
		(fp_line
			(start 0.12065 -0.3048)
			(end 0.67945 -0.3048)
			(stroke
				(width 0.1)
				(type default)
			)
			(layer "F.Fab")
		)
		(fp_line
			(start 0.120396 0.3048)
			(end 0.120396 0.2794)
			(stroke
				(width 0.1)
				(type default)
			)
			(layer "F.Fab")
		)
		(fp_line
			(start 0.120396 0.2794)
			(end -0.12065 0.2794)
			(stroke
				(width 0.1)
				(type default)
			)
			(layer "F.Fab")
		)
		(fp_line
			(start -0.12065 0.3048)
			(end -0.67945 0.3048)
			(stroke
				(width 0.1)
				(type default)
			)
			(layer "F.Fab")
		)
		(fp_line
			(start -0.12065 0.2794)
			(end -0.12065 0.3048)
			(stroke
				(width 0.1)
				(type default)
			)
			(layer "F.Fab")
		)
		(fp_line
			(start -0.12065 -0.2794)
			(end 0.12065 -0.2794)
			(stroke
				(width 0.1)
				(type default)
			)
			(layer "F.Fab")
		)
		(fp_line
			(start -0.12065 -0.305054)
			(end -0.12065 -0.2794)
			(stroke
				(width 0.1)
				(type default)
			)
			(layer "F.Fab")
		)
		(fp_line
			(start -0.67945 0.3048)
			(end -0.67945 -0.305054)
			(stroke
				(width 0.1)
				(type default)
			)
			(layer "F.Fab")
		)
		(fp_line
			(start -0.67945 -0.305054)
			(end -0.12065 -0.305054)
			(stroke
				(width 0.1)
				(type default)
			)
			(layer "F.Fab")
		)
		(pad "1" smd circle
			(at -0.40005 0 180)
			(size 0 0)
			(layers "F.Cu" "F.Mask" "F.Paste")
			(net "GND")
		)
		(pad "2" smd circle
			(at 0.40005 0 180)
			(size 0 0)
			(layers "F.Cu" "F.Mask" "F.Paste")
			(net "RST_PEX1_PERST_R_N")
		)
	)
	(footprint ""
		(layer "F.Cu")
		(at 358.013 -221.488)
		(property "Reference" "R3647"
			(at 0 0 0)
			(layer "F.SilkS")
			(hide yes)
			(effects
				(font
					(size 1.27 1.27)
				)
			)
		)
		(property "Value" ""
			(at 0 0 0)
			(layer "F.Fab")
			(effects
				(font
					(size 1.27 1.27)
				)
			)
		)
		(duplicate_pad_numbers_are_jumpers no)
		(fp_line
			(start -0.7874 -0.4064)
			(end 0.7874 -0.4064)
			(stroke
				(width 0.1524)
				(type default)
			)
			(layer "F.SilkS")
		)
		(fp_line
			(start -0.7874 0.4064)
			(end -0.7874 -0.4064)
			(stroke
				(width 0.1524)
				(type default)
			)
			(layer "F.SilkS")
		)
		(fp_line
			(start 0.7874 -0.4064)
			(end 0.7874 0.4064)
			(stroke
				(width 0.1524)
				(type default)
			)
			(layer "F.SilkS")
		)
		(fp_line
			(start 0.7874 0.4064)
			(end -0.7874 0.4064)
			(stroke
				(width 0.1524)
				(type default)
			)
			(layer "F.SilkS")
		)
		(fp_line
			(start -0.67945 -0.305054)
			(end -0.12065 -0.305054)
			(stroke
				(width 0.1)
				(type default)
			)
			(layer "F.Fab")
		)
		(fp_line
			(start -0.67945 0.3048)
			(end -0.67945 -0.305054)
			(stroke
				(width 0.1)
				(type default)
			)
			(layer "F.Fab")
		)
		(fp_line
			(start -0.12065 -0.305054)
			(end -0.12065 -0.2794)
			(stroke
				(width 0.1)
				(type default)
			)
			(layer "F.Fab")
		)
		(fp_line
			(start -0.12065 -0.2794)
			(end 0.12065 -0.2794)
			(stroke
				(width 0.1)
				(type default)
			)
			(layer "F.Fab")
		)
		(fp_line
			(start -0.12065 0.2794)
			(end -0.12065 0.3048)
			(stroke
				(width 0.1)
				(type default)
			)
			(layer "F.Fab")
		)
		(fp_line
			(start -0.12065 0.3048)
			(end -0.67945 0.3048)
			(stroke
				(width 0.1)
				(type default)
			)
			(layer "F.Fab")
		)
		(fp_line
			(start 0.120396 0.2794)
			(end -0.12065 0.2794)
			(stroke
				(width 0.1)
				(type default)
			)
			(layer "F.Fab")
		)
		(fp_line
			(start 0.120396 0.3048)
			(end 0.120396 0.2794)
			(stroke
				(width 0.1)
				(type default)
			)
			(layer "F.Fab")
		)
		(fp_line
			(start 0.12065 -0.3048)
			(end 0.67945 -0.3048)
			(stroke
				(width 0.1)
				(type default)
			)
			(layer "F.Fab")
		)
		(fp_line
			(start 0.12065 -0.2794)
			(end 0.12065 -0.3048)
			(stroke
				(width 0.1)
				(type default)
			)
			(layer "F.Fab")
		)
		(fp_line
			(start 0.67945 -0.3048)
			(end 0.67945 0.3048)
			(stroke
				(width 0.1)
				(type default)
			)
			(layer "F.Fab")
		)
		(fp_line
			(start 0.67945 0.3048)
			(end 0.120396 0.3048)
			(stroke
				(width 0.1)
				(type default)
			)
			(layer "F.Fab")
		)
		(pad "1" smd circle
			(at -0.40005 0)
			(size 0 0)
			(layers "F.Cu" "F.Mask" "F.Paste")
			(net "RST_NIC5_PERST_N")
		)
		(pad "2" smd circle
			(at 0.40005 0)
			(size 0 0)
			(layers "F.Cu" "F.Mask" "F.Paste")
			(net "RST_NIC5_PERST_R_N")
		)
	)
	(footprint ""
		(layer "F.Cu")
		(at 302.838612 -22.867366 90)
		(property "Reference" "C3947"
			(at 0 0 90)
			(layer "F.SilkS")
			(hide yes)
			(effects
				(font
					(size 1.27 1.27)
				)
			)
		)
		(property "Value" ""
			(at 0 0 90)
			(layer "F.Fab")
			(effects
				(font
					(size 1.27 1.27)
				)
			)
		)
		(duplicate_pad_numbers_are_jumpers no)
		(fp_line
			(start 0.7874 -0.4064)
			(end 0.7874 0.4064)
			(stroke
				(width 0.1524)
				(type default)
			)
			(layer "F.SilkS")
		)
		(fp_line
			(start -0.7874 -0.4064)
			(end 0.7874 -0.4064)
			(stroke
				(width 0.1524)
				(type default)
			)
			(layer "F.SilkS")
		)
		(fp_line
			(start 0.7874 0.4064)
			(end -0.7874 0.4064)
			(stroke
				(width 0.1524)
				(type default)
			)
			(layer "F.SilkS")
		)
		(fp_line
			(start -0.7874 0.4064)
			(end -0.7874 -0.4064)
			(stroke
				(width 0.1524)
				(type default)
			)
			(layer "F.SilkS")
		)
		(fp_line
			(start -0.12065 -0.305054)
			(end -0.12065 -0.2794)
			(stroke
				(width 0.1)
				(type default)
			)
			(layer "F.Fab")
		)
		(fp_line
			(start -0.67945 -0.305054)
			(end -0.12065 -0.305054)
			(stroke
				(width 0.1)
				(type default)
			)
			(layer "F.Fab")
		)
		(fp_line
			(start 0.67945 -0.3048)
			(end 0.67945 0.3048)
			(stroke
				(width 0.1)
				(type default)
			)
			(layer "F.Fab")
		)
		(fp_line
			(start 0.12065 -0.3048)
			(end 0.67945 -0.3048)
			(stroke
				(width 0.1)
				(type default)
			)
			(layer "F.Fab")
		)
		(fp_line
			(start 0.12065 -0.2794)
			(end 0.12065 -0.3048)
			(stroke
				(width 0.1)
				(type default)
			)
			(layer "F.Fab")
		)
		(fp_line
			(start -0.12065 -0.2794)
			(end 0.12065 -0.2794)
			(stroke
				(width 0.1)
				(type default)
			)
			(layer "F.Fab")
		)
		(fp_line
			(start 0.120396 0.2794)
			(end -0.12065 0.2794)
			(stroke
				(width 0.1)
				(type default)
			)
			(layer "F.Fab")
		)
		(fp_line
			(start -0.12065 0.2794)
			(end -0.12065 0.3048)
			(stroke
				(width 0.1)
				(type default)
			)
			(layer "F.Fab")
		)
		(fp_line
			(start 0.67945 0.3048)
			(end 0.120396 0.3048)
			(stroke
				(width 0.1)
				(type default)
			)
			(layer "F.Fab")
		)
		(fp_line
			(start 0.120396 0.3048)
			(end 0.120396 0.2794)
			(stroke
				(width 0.1)
				(type default)
			)
			(layer "F.Fab")
		)
		(fp_line
			(start -0.12065 0.3048)
			(end -0.67945 0.3048)
			(stroke
				(width 0.1)
				(type default)
			)
			(layer "F.Fab")
		)
		(fp_line
			(start -0.67945 0.3048)
			(end -0.67945 -0.305054)
			(stroke
				(width 0.1)
				(type default)
			)
			(layer "F.Fab")
		)
		(pad "1" smd circle
			(at -0.40005 0 90)
			(size 0 0)
			(layers "F.Cu" "F.Mask" "F.Paste")
			(net "P12V_SSD10")
		)
		(pad "2" smd circle
			(at 0.40005 0 90)
			(size 0 0)
			(layers "F.Cu" "F.Mask" "F.Paste")
			(net "GND")
		)
	)
	(footprint ""
		(layer "F.Cu")
		(at 215.075516 -121.255028)
		(property "Reference" "PC337"
			(at 0 0 0)
			(layer "F.SilkS")
			(hide yes)
			(effects
				(font
					(size 1.27 1.27)
				)
			)
		)
		(property "Value" ""
			(at 0 0 0)
			(layer "F.Fab")
			(effects
				(font
					(size 1.27 1.27)
				)
			)
		)
		(duplicate_pad_numbers_are_jumpers no)
		(fp_line
			(start -0.7874 -0.4064)
			(end 0.7874 -0.4064)
			(stroke
				(width 0.1524)
				(type default)
			)
			(layer "F.SilkS")
		)
		(fp_line
			(start -0.7874 0.4064)
			(end -0.7874 -0.4064)
			(stroke
				(width 0.1524)
				(type default)
			)
			(layer "F.SilkS")
		)
		(fp_line
			(start 0.7874 -0.4064)
			(end 0.7874 0.4064)
			(stroke
				(width 0.1524)
				(type default)
			)
			(layer "F.SilkS")
		)
		(fp_line
			(start 0.7874 0.4064)
			(end -0.7874 0.4064)
			(stroke
				(width 0.1524)
				(type default)
			)
			(layer "F.SilkS")
		)
		(fp_line
			(start -0.67945 -0.305054)
			(end -0.12065 -0.305054)
			(stroke
				(width 0.1)
				(type default)
			)
			(layer "F.Fab")
		)
		(fp_line
			(start -0.67945 0.3048)
			(end -0.67945 -0.305054)
			(stroke
				(width 0.1)
				(type default)
			)
			(layer "F.Fab")
		)
		(fp_line
			(start -0.12065 -0.305054)
			(end -0.12065 -0.2794)
			(stroke
				(width 0.1)
				(type default)
			)
			(layer "F.Fab")
		)
		(fp_line
			(start -0.12065 -0.2794)
			(end 0.12065 -0.2794)
			(stroke
				(width 0.1)
				(type default)
			)
			(layer "F.Fab")
		)
		(fp_line
			(start -0.12065 0.2794)
			(end -0.12065 0.3048)
			(stroke
				(width 0.1)
				(type default)
			)
			(layer "F.Fab")
		)
		(fp_line
			(start -0.12065 0.3048)
			(end -0.67945 0.3048)
			(stroke
				(width 0.1)
				(type default)
			)
			(layer "F.Fab")
		)
		(fp_line
			(start 0.120396 0.2794)
			(end -0.12065 0.2794)
			(stroke
				(width 0.1)
				(type default)
			)
			(layer "F.Fab")
		)
		(fp_line
			(start 0.120396 0.3048)
			(end 0.120396 0.2794)
			(stroke
				(width 0.1)
				(type default)
			)
			(layer "F.Fab")
		)
		(fp_line
			(start 0.12065 -0.3048)
			(end 0.67945 -0.3048)
			(stroke
				(width 0.1)
				(type default)
			)
			(layer "F.Fab")
		)
		(fp_line
			(start 0.12065 -0.2794)
			(end 0.12065 -0.3048)
			(stroke
				(width 0.1)
				(type default)
			)
			(layer "F.Fab")
		)
		(fp_line
			(start 0.67945 -0.3048)
			(end 0.67945 0.3048)
			(stroke
				(width 0.1)
				(type default)
			)
			(layer "F.Fab")
		)
		(fp_line
			(start 0.67945 0.3048)
			(end 0.120396 0.3048)
			(stroke
				(width 0.1)
				(type default)
			)
			(layer "F.Fab")
		)
		(pad "1" smd circle
			(at -0.40005 0)
			(size 0 0)
			(layers "F.Cu" "F.Mask" "F.Paste")
			(net "P5V_AUX")
		)
		(pad "2" smd circle
			(at 0.40005 0)
			(size 0 0)
			(layers "F.Cu" "F.Mask" "F.Paste")
			(net "GND")
		)
	)
)
